# S9S_MB_2U (Grand Teton) — schematic netlist excerpt (pin names and nets, part order shuffled) for the footprints in the layout excerpt that follows; sources: Cadence DE-HDL packaged netlist, KiCad conversion of 03242023_DA0F0TMBIJ0_F0T_Motherboard_J_brd_V01_OCP.brd

L2  Q_INDUCTOR  BLM15PX121SN1D/2A EMPTY  pkg SMLF  page 189 : \1\ = P1V05_PCH_AUX ; \2\ = P1V05_PCH_PLL_AUX
R181  Q_RES  100 1% CHIP  pkg 0402LF  page 124 : A = PWRGD_DRAMPWRGD_CPU0_GH_LVC1_R2 ; B = PVCCD_HV_CPU0

(kicad_pcb
	(version 20260206)
	(generator "pcbnew")
	(generator_version "10.0")
	(general
		(thickness 1.6)
		(legacy_teardrops no)
	)
	(paper "A4")
	(title_block
		(title "03242023_DA0F0TMBIJ0_F0T_Motherboard_J_brd_V01_OCP.brd")
		(comment 1 "Grand Teton / footprints 4609-4610 of 6105")
	)
	(layers
		(0 "F.Cu" signal "TOP")
		(4 "In1.Cu" signal "GND")
		(6 "In2.Cu" signal "IN1")
		(8 "In3.Cu" signal "GND1")
		(10 "In4.Cu" signal "IN2")
		(12 "In5.Cu" signal "GND2")
		(14 "In6.Cu" signal "IN3")
		(16 "In7.Cu" signal "GND3")
		(18 "In8.Cu" signal "VCC")
		(20 "In9.Cu" signal "VCC1")
		(22 "In10.Cu" signal "GND4")
		(24 "In11.Cu" signal "IN4")
		(26 "In12.Cu" signal "GND5")
		(28 "In13.Cu" signal "IN5")
		(30 "In14.Cu" signal "GND6")
		(32 "In15.Cu" signal "IN6")
		(34 "In16.Cu" signal "GND7")
		(2 "B.Cu" signal "BOTTOM")
		(9 "F.Adhes" user "F.Adhesive")
		(11 "B.Adhes" user "B.Adhesive")
		(13 "F.Paste" user "Package Geometry/Pastemask Top")
		(15 "B.Paste" user "Package Geometry/Pastemask Bottom")
		(5 "F.SilkS" user "Ref Des/Silkscreen Top")
		(7 "B.SilkS" user "Ref Des/Silkscreen Bottom")
		(1 "F.Mask" user "Board Geometry/Soldermask Top")
		(3 "B.Mask" user "Board Geometry/Soldermask Bottom")
		(17 "Dwgs.User" user "User.Drawings")
		(19 "Cmts.User" user "User.Comments")
		(21 "Eco1.User" user "User.Eco1")
		(23 "Eco2.User" user "User.Eco2")
		(25 "Edge.Cuts" user "Board Geometry/Outline")
		(27 "Margin" user)
		(31 "F.CrtYd" user "Package Geometry/Place Bound Top")
		(29 "B.CrtYd" user "Package Geometry/Place Bound Bottom")
		(35 "F.Fab" user "Ref Des/Assembly Top")
		(33 "B.Fab" user "Ref Des/Assembly Bottom")
	)
	(footprint ""
		(layer "B.Cu")
		(at 400.686778 -190.77559 90)
		(property "Reference" "R181"
			(at 0 0 90)
			(layer "B.SilkS")
			(hide yes)
			(effects
				(font
					(size 1.27 1.27)
				)
				(justify mirror)
			)
		)
		(property "Value" ""
			(at 0 0 90)
			(layer "B.Fab")
			(effects
				(font
					(size 1.27 1.27)
				)
				(justify mirror)
			)
		)
		(duplicate_pad_numbers_are_jumpers no)
		(fp_line
			(start 0.7874 -0.4064)
			(end -0.7874 -0.4064)
			(stroke
				(width 0.1524)
				(type default)
			)
			(layer "B.SilkS")
		)
		(fp_line
			(start -0.7874 -0.4064)
			(end -0.7874 0.4064)
			(stroke
				(width 0.1524)
				(type default)
			)
			(layer "B.SilkS")
		)
		(fp_line
			(start 0.7874 0.4064)
			(end 0.7874 -0.4064)
			(stroke
				(width 0.1524)
				(type default)
			)
			(layer "B.SilkS")
		)
		(fp_line
			(start -0.7874 0.4064)
			(end 0.7874 0.4064)
			(stroke
				(width 0.1524)
				(type default)
			)
			(layer "B.SilkS")
		)
		(fp_line
			(start 0.67945 -0.305054)
			(end 0.12065 -0.305054)
			(stroke
				(width 0.1)
				(type default)
			)
			(layer "B.Fab")
		)
		(fp_line
			(start 0.12065 -0.305054)
			(end 0.12065 -0.2794)
			(stroke
				(width 0.1)
				(type default)
			)
			(layer "B.Fab")
		)
		(fp_line
			(start -0.12065 -0.3048)
			(end -0.67945 -0.3048)
			(stroke
				(width 0.1)
				(type default)
			)
			(layer "B.Fab")
		)
		(fp_line
			(start -0.67945 -0.3048)
			(end -0.67945 0.3048)
			(stroke
				(width 0.1)
				(type default)
			)
			(layer "B.Fab")
		)
		(fp_line
			(start 0.12065 -0.2794)
			(end -0.12065 -0.2794)
			(stroke
				(width 0.1)
				(type default)
			)
			(layer "B.Fab")
		)
		(fp_line
			(start -0.12065 -0.2794)
			(end -0.12065 -0.3048)
			(stroke
				(width 0.1)
				(type default)
			)
			(layer "B.Fab")
		)
		(fp_line
			(start 0.12065 0.2794)
			(end 0.12065 0.3048)
			(stroke
				(width 0.1)
				(type default)
			)
			(layer "B.Fab")
		)
		(fp_line
			(start -0.120396 0.2794)
			(end 0.12065 0.2794)
			(stroke
				(width 0.1)
				(type default)
			)
			(layer "B.Fab")
		)
		(fp_line
			(start 0.67945 0.3048)
			(end 0.67945 -0.305054)
			(stroke
				(width 0.1)
				(type default)
			)
			(layer "B.Fab")
		)
		(fp_line
			(start 0.12065 0.3048)
			(end 0.67945 0.3048)
			(stroke
				(width 0.1)
				(type default)
			)
			(layer "B.Fab")
		)
		(fp_line
			(start -0.120396 0.3048)
			(end -0.120396 0.2794)
			(stroke
				(width 0.1)
				(type default)
			)
			(layer "B.Fab")
		)
		(fp_line
			(start -0.67945 0.3048)
			(end -0.120396 0.3048)
			(stroke
				(width 0.1)
				(type default)
			)
			(layer "B.Fab")
		)
		(pad "1" smd circle
			(at 0.40005 0 270)
			(size 0 0)
			(layers "B.Cu" "B.Mask" "B.Paste")
			(net "PWRGD_DRAMPWRGD_CPU0_GH_LVC1_R2")
		)
		(pad "2" smd circle
			(at -0.40005 0 270)
			(size 0 0)
			(layers "B.Cu" "B.Mask" "B.Paste")
			(net "PVCCD_HV_CPU0")
		)
	)
	(footprint ""
		(layer "B.Cu")
		(at 327.15708 -68.339208 90)
		(property "Reference" "L2"
			(at 0 0 90)
			(layer "B.SilkS")
			(hide yes)
			(effects
				(font
					(size 1.27 1.27)
				)
				(justify mirror)
			)
		)
		(property "Value" ""
			(at 0 0 90)
			(layer "B.Fab")
			(effects
				(font
					(size 1.27 1.27)
				)
				(justify mirror)
			)
		)
		(duplicate_pad_numbers_are_jumpers no)
		(fp_line
			(start 0.762 -0.381)
			(end -0.762 -0.381)
			(stroke
				(width 0.1524)
				(type default)
			)
			(layer "B.SilkS")
		)
		(fp_line
			(start -0.762 -0.381)
			(end -0.762 0.381)
			(stroke
				(width 0.1524)
				(type default)
			)
			(layer "B.SilkS")
		)
		(fp_line
			(start 0.762 0.381)
			(end 0.762 -0.381)
			(stroke
				(width 0.1524)
				(type default)
			)
			(layer "B.SilkS")
		)
		(fp_line
			(start -0.762 0.381)
			(end 0.762 0.381)
			(stroke
				(width 0.1524)
				(type default)
			)
			(layer "B.SilkS")
		)
		(fp_line
			(start 0.681736 -0.307086)
			(end 0.118364 -0.307086)
			(stroke
				(width 0.1)
				(type default)
			)
			(layer "B.Fab")
		)
		(fp_line
			(start 0.118364 -0.307086)
			(end 0.118364 -0.2794)
			(stroke
				(width 0.1)
				(type default)
			)
			(layer "B.Fab")
		)
		(fp_line
			(start -0.118872 -0.306324)
			(end -0.680466 -0.306324)
			(stroke
				(width 0.1)
				(type default)
			)
			(layer "B.Fab")
		)
		(fp_line
			(start -0.680466 -0.306324)
			(end -0.680466 0.306324)
			(stroke
				(width 0.1)
				(type default)
			)
			(layer "B.Fab")
		)
		(fp_line
			(start 0.118364 -0.2794)
			(end -0.118872 -0.2794)
			(stroke
				(width 0.1)
				(type default)
			)
			(layer "B.Fab")
		)
		(fp_line
			(start -0.118872 -0.2794)
			(end -0.118872 -0.306324)
			(stroke
				(width 0.1)
				(type default)
			)
			(layer "B.Fab")
		)
		(fp_line
			(start 0.119634 0.2794)
			(end 0.119634 0.30607)
			(stroke
				(width 0.1)
				(type default)
			)
			(layer "B.Fab")
		)
		(fp_line
			(start -0.118364 0.2794)
			(end 0.119634 0.2794)
			(stroke
				(width 0.1)
				(type default)
			)
			(layer "B.Fab")
		)
		(fp_line
			(start 0.681736 0.30607)
			(end 0.681736 -0.307086)
			(stroke
				(width 0.1)
				(type default)
			)
			(layer "B.Fab")
		)
		(fp_line
			(start 0.119634 0.30607)
			(end 0.681736 0.30607)
			(stroke
				(width 0.1)
				(type default)
			)
			(layer "B.Fab")
		)
		(fp_line
			(start -0.118364 0.306324)
			(end -0.118364 0.2794)
			(stroke
				(width 0.1)
				(type default)
			)
			(layer "B.Fab")
		)
		(fp_line
			(start -0.680466 0.306324)
			(end -0.118364 0.306324)
			(stroke
				(width 0.1)
				(type default)
			)
			(layer "B.Fab")
		)
		(pad "1" smd rect
			(at 0.40005 0 90)
			(size 0.4572 0.508)
			(layers "B.Cu" "B.Mask" "B.Paste")
			(net "P1V05_PCH_AUX")
		)
		(pad "2" smd rect
			(at -0.40005 0 90)
			(size 0.4572 0.508)
			(layers "B.Cu" "B.Mask" "B.Paste")
			(net "P1V05_PCH_PLL_AUX")
		)
	)
)
